# S9S_MB_2U (Grand Teton) — schematic netlist excerpt (pin names and nets, part order shuffled) for the footprints in the layout excerpt that follows; sources: Cadence DE-HDL packaged netlist, KiCad conversion of 03242023_DA0F0TMBIJ0_F0T_Motherboard_J_brd_V01_OCP.brd

R3772  Q_RES  0 5% CHIP  pkg 0402LF  page 191 : A = RST_SMB_BUF_E1S_0_N ; B = RST_SMB_E1S_0_N
C977  Q_CAP  10UF 6.3V 20% X6S  pkg C0402  page 74 : A = PVCCIN_CPU0 ; B = GND

(kicad_pcb
	(version 20260206)
	(generator "pcbnew")
	(generator_version "10.0")
	(general
		(thickness 1.6)
		(legacy_teardrops no)
	)
	(paper "A4")
	(title_block
		(title "03242023_DA0F0TMBIJ0_F0T_Motherboard_J_brd_V01_OCP.brd")
		(comment 1 "Grand Teton / footprints 3262-3263 of 6105")
	)
	(layers
		(0 "F.Cu" signal "TOP")
		(4 "In1.Cu" signal "GND")
		(6 "In2.Cu" signal "IN1")
		(8 "In3.Cu" signal "GND1")
		(10 "In4.Cu" signal "IN2")
		(12 "In5.Cu" signal "GND2")
		(14 "In6.Cu" signal "IN3")
		(16 "In7.Cu" signal "GND3")
		(18 "In8.Cu" signal "VCC")
		(20 "In9.Cu" signal "VCC1")
		(22 "In10.Cu" signal "GND4")
		(24 "In11.Cu" signal "IN4")
		(26 "In12.Cu" signal "GND5")
		(28 "In13.Cu" signal "IN5")
		(30 "In14.Cu" signal "GND6")
		(32 "In15.Cu" signal "IN6")
		(34 "In16.Cu" signal "GND7")
		(2 "B.Cu" signal "BOTTOM")
		(9 "F.Adhes" user "F.Adhesive")
		(11 "B.Adhes" user "B.Adhesive")
		(13 "F.Paste" user "Package Geometry/Pastemask Top")
		(15 "B.Paste" user "Package Geometry/Pastemask Bottom")
		(5 "F.SilkS" user "Ref Des/Silkscreen Top")
		(7 "B.SilkS" user "Ref Des/Silkscreen Bottom")
		(1 "F.Mask" user "Board Geometry/Soldermask Top")
		(3 "B.Mask" user "Board Geometry/Soldermask Bottom")
		(17 "Dwgs.User" user "User.Drawings")
		(19 "Cmts.User" user "User.Comments")
		(21 "Eco1.User" user "User.Eco1")
		(23 "Eco2.User" user "User.Eco2")
		(25 "Edge.Cuts" user "Board Geometry/Outline")
		(27 "Margin" user)
		(31 "F.CrtYd" user "Package Geometry/Place Bound Top")
		(29 "B.CrtYd" user "Package Geometry/Place Bound Bottom")
		(35 "F.Fab" user "Ref Des/Assembly Top")
		(33 "B.Fab" user "Ref Des/Assembly Bottom")
	)
	(footprint ""
		(layer "F.Cu")
		(at 159.655256 -66.091308)
		(property "Reference" "R3772"
			(at 0 0 0)
			(layer "F.SilkS")
			(hide yes)
			(effects
				(font
					(size 1.27 1.27)
				)
			)
		)
		(property "Value" ""
			(at 0 0 0)
			(layer "F.Fab")
			(effects
				(font
					(size 1.27 1.27)
				)
			)
		)
		(duplicate_pad_numbers_are_jumpers no)
		(fp_line
			(start -0.7874 -0.4064)
			(end 0.7874 -0.4064)
			(stroke
				(width 0.1524)
				(type default)
			)
			(layer "F.SilkS")
		)
		(fp_line
			(start -0.7874 0.4064)
			(end -0.7874 -0.4064)
			(stroke
				(width 0.1524)
				(type default)
			)
			(layer "F.SilkS")
		)
		(fp_line
			(start 0.7874 -0.4064)
			(end 0.7874 0.4064)
			(stroke
				(width 0.1524)
				(type default)
			)
			(layer "F.SilkS")
		)
		(fp_line
			(start 0.7874 0.4064)
			(end -0.7874 0.4064)
			(stroke
				(width 0.1524)
				(type default)
			)
			(layer "F.SilkS")
		)
		(fp_line
			(start -0.67945 -0.305054)
			(end -0.12065 -0.305054)
			(stroke
				(width 0.1)
				(type default)
			)
			(layer "F.Fab")
		)
		(fp_line
			(start -0.67945 0.3048)
			(end -0.67945 -0.305054)
			(stroke
				(width 0.1)
				(type default)
			)
			(layer "F.Fab")
		)
		(fp_line
			(start -0.12065 -0.305054)
			(end -0.12065 -0.2794)
			(stroke
				(width 0.1)
				(type default)
			)
			(layer "F.Fab")
		)
		(fp_line
			(start -0.12065 -0.2794)
			(end 0.12065 -0.2794)
			(stroke
				(width 0.1)
				(type default)
			)
			(layer "F.Fab")
		)
		(fp_line
			(start -0.12065 0.2794)
			(end -0.12065 0.3048)
			(stroke
				(width 0.1)
				(type default)
			)
			(layer "F.Fab")
		)
		(fp_line
			(start -0.12065 0.3048)
			(end -0.67945 0.3048)
			(stroke
				(width 0.1)
				(type default)
			)
			(layer "F.Fab")
		)
		(fp_line
			(start 0.120396 0.2794)
			(end -0.12065 0.2794)
			(stroke
				(width 0.1)
				(type default)
			)
			(layer "F.Fab")
		)
		(fp_line
			(start 0.120396 0.3048)
			(end 0.120396 0.2794)
			(stroke
				(width 0.1)
				(type default)
			)
			(layer "F.Fab")
		)
		(fp_line
			(start 0.12065 -0.3048)
			(end 0.67945 -0.3048)
			(stroke
				(width 0.1)
				(type default)
			)
			(layer "F.Fab")
		)
		(fp_line
			(start 0.12065 -0.2794)
			(end 0.12065 -0.3048)
			(stroke
				(width 0.1)
				(type default)
			)
			(layer "F.Fab")
		)
		(fp_line
			(start 0.67945 -0.3048)
			(end 0.67945 0.3048)
			(stroke
				(width 0.1)
				(type default)
			)
			(layer "F.Fab")
		)
		(fp_line
			(start 0.67945 0.3048)
			(end 0.120396 0.3048)
			(stroke
				(width 0.1)
				(type default)
			)
			(layer "F.Fab")
		)
		(pad "1" smd circle
			(at -0.40005 0)
			(size 0 0)
			(layers "F.Cu" "F.Mask" "F.Paste")
			(net "RST_SMB_BUF_E1S_0_N")
		)
		(pad "2" smd circle
			(at 0.40005 0)
			(size 0 0)
			(layers "F.Cu" "F.Mask" "F.Paste")
			(net "RST_SMB_E1S_0_N")
		)
	)
	(footprint ""
		(layer "F.Cu")
		(at 366.48263 -249.320304 -90)
		(property "Reference" "C977"
			(at 0 0 270)
			(layer "F.SilkS")
			(hide yes)
			(effects
				(font
					(size 1.27 1.27)
				)
			)
		)
		(property "Value" ""
			(at 0 0 270)
			(layer "F.Fab")
			(effects
				(font
					(size 1.27 1.27)
				)
			)
		)
		(duplicate_pad_numbers_are_jumpers no)
		(fp_line
			(start -0.7874 0.4064)
			(end -0.7874 -0.4064)
			(stroke
				(width 0.1524)
				(type default)
			)
			(layer "F.SilkS")
		)
		(fp_line
			(start 0.7874 0.4064)
			(end -0.7874 0.4064)
			(stroke
				(width 0.1524)
				(type default)
			)
			(layer "F.SilkS")
		)
		(fp_line
			(start -0.7874 -0.4064)
			(end 0.7874 -0.4064)
			(stroke
				(width 0.1524)
				(type default)
			)
			(layer "F.SilkS")
		)
		(fp_line
			(start 0.7874 -0.4064)
			(end 0.7874 0.4064)
			(stroke
				(width 0.1524)
				(type default)
			)
			(layer "F.SilkS")
		)
		(fp_line
			(start -0.67945 0.3048)
			(end -0.67945 -0.305054)
			(stroke
				(width 0.1)
				(type default)
			)
			(layer "F.Fab")
		)
		(fp_line
			(start -0.12065 0.3048)
			(end -0.67945 0.3048)
			(stroke
				(width 0.1)
				(type default)
			)
			(layer "F.Fab")
		)
		(fp_line
			(start 0.120396 0.3048)
			(end 0.120396 0.2794)
			(stroke
				(width 0.1)
				(type default)
			)
			(layer "F.Fab")
		)
		(fp_line
			(start 0.67945 0.3048)
			(end 0.120396 0.3048)
			(stroke
				(width 0.1)
				(type default)
			)
			(layer "F.Fab")
		)
		(fp_line
			(start -0.12065 0.2794)
			(end -0.12065 0.3048)
			(stroke
				(width 0.1)
				(type default)
			)
			(layer "F.Fab")
		)
		(fp_line
			(start 0.120396 0.2794)
			(end -0.12065 0.2794)
			(stroke
				(width 0.1)
				(type default)
			)
			(layer "F.Fab")
		)
		(fp_line
			(start -0.12065 -0.2794)
			(end 0.12065 -0.2794)
			(stroke
				(width 0.1)
				(type default)
			)
			(layer "F.Fab")
		)
		(fp_line
			(start 0.12065 -0.2794)
			(end 0.12065 -0.3048)
			(stroke
				(width 0.1)
				(type default)
			)
			(layer "F.Fab")
		)
		(fp_line
			(start 0.12065 -0.3048)
			(end 0.67945 -0.3048)
			(stroke
				(width 0.1)
				(type default)
			)
			(layer "F.Fab")
		)
		(fp_line
			(start 0.67945 -0.3048)
			(end 0.67945 0.3048)
			(stroke
				(width 0.1)
				(type default)
			)
			(layer "F.Fab")
		)
		(fp_line
			(start -0.67945 -0.305054)
			(end -0.12065 -0.305054)
			(stroke
				(width 0.1)
				(type default)
			)
			(layer "F.Fab")
		)
		(fp_line
			(start -0.12065 -0.305054)
			(end -0.12065 -0.2794)
			(stroke
				(width 0.1)
				(type default)
			)
			(layer "F.Fab")
		)
		(pad "1" smd circle
			(at -0.40005 0 270)
			(size 0 0)
			(layers "F.Cu" "F.Mask" "F.Paste")
			(net "PVCCIN_CPU0")
		)
		(pad "2" smd circle
			(at 0.40005 0 270)
			(size 0 0)
			(layers "F.Cu" "F.Mask" "F.Paste")
			(net "GND")
		)
	)
)
